FILE_TYPE = CONNECTIVITY;
{Allegro Design Entry HDL 16.6-p007 (v16-6-112F) 10/10/2012}
"PAGE_NUMBER" = 176;
0"NC";
1"P5V\g";
2"GND\g";
3"GND\g";
4"P3V3_STBY\g";
5"GND\g";
6"GND\g";
7"GND\g";
8"P3V3_STBY\g";
9"GND\g";
10"GND\g";
11"GND\g";
12"SPA_MID_DBG_RX";
13"SMB_IPMB_3V3AUX_SCL";
14"SMB_IPMB_3V3AUX_SDA";
15"FM_UART_SWITCH_N";
16"SPA_MID_DBG1__RX";
17"SPA_MID_DBG2_RX";
18"USB2_P01_ESD_DN";
19"USB2_P01_ESD_DP";
20"TP_USB_ESD_OUT2";
21"TP_USB_ESD_OUT3";
22"P5V_USB"VOLTAGE"5V";
23"USB2_P01_DP";
24"USB2_P01_DN";
25"FM_USB_P0_EN_BOOT_BIOS_STRAP_N";
26"SPA_MID_DBG2_RX";
27"SPA_MID_DBG_TX";
28"P5V_USB";
29"TP_USB_ESD_AC3";
30"FM_OC0_USB_N";
31"TP_USB_ESD_AC2";
%"TPS2061"
"1","(-1100,1825)","0","mstr_vreg","I100";
;
CDS_SEC"1"
CDS_LOCATION"U1M3"
CDS_LIB"mstr_vreg"
PACK_TYPE"SM"
SEC_TYPE"SM"
BOM_COST"MIO_USB"
SEC"1"
ROOM"USB_REAR"
LOCATION"U1M3"
MATERIAL"IC"
PART_NUMBER"H66405-001";
"IN"
$PN"5"1;
"EN_N"
$PN"4"25;
"OUT"
$PN"1"28;
"GND"
$PN"2"2;
"OC_N"
$PN"3"30;
%"P5V"
"1","(-1800,2600)","0","mstr_symbols","I101";
;
HDL_POWER"P5V"
BODY_TYPE"PLUMBING"
VOLTAGE"5.0V"
SIZE"1B"
CDS_LIB"mstr_symbols";
"G\NAC"1;
%"GND"
"1","(-725,1450)","0","mstr_symbols","I102";
;
CDS_LIB"mstr_symbols"
BODY_TYPE"PLUMBING"
HDL_POWER"GND"
VOLTAGE"0"
SIZE"1B";
"A\NAC"2;
%"RES"
"2","(-675,2300)","0","mstr_discrete","I105";
;
CDS_SEC"1"
CDS_LOCATION"R1M24"
CDS_LIB"mstr_discrete"
ROOM"USB_REAR"
SEC"1"
SEC_TYPE"0402"
BOM_COST"MIO_USB"
VALUE"10.0K"
PACK_TYPE"0402"
WATTAGE"1/16W"
MATERIAL"CHIP"
PART_NUMBER"G21796-016"
TOLERANCE"1%"
LOCATION"R1M24";
"A"
$PN"1"4;
"B"
$PN"2"30;
%"CAP_A"
"1","(-2075,2250)","0","dev_discrete","I108";
;
CDS_LOCATION"C1M38"
CDS_LIB"dev_discrete"
ROOM"USB_REAR"
CDS_SEC"1"
SEC"1"
SEC_TYPE"0402V"
BOM_COST"MIO_USB"
TOLERANCE"10%"
MATERIAL"X7R"
VOLTAGE"16V"
VALUE"0.1UF"
PACK_TYPE"0402V"
PART_NUMBER"A36096-030"
LOCATION"C1M38";
"B"
$PN"2"3;
"A"
$PN"1"1;
%"GND"
"1","(-2075,1950)","0","mstr_symbols","I109";
;
HDL_POWER"GND"
BODY_TYPE"PLUMBING"
CDS_LIB"mstr_symbols"
VOLTAGE"0"
SIZE"1B";
"A\NAC"3;
%"P3V3_STBY"
"1","(-675,2575)","0","mstr_symbols","I110";
;
HDL_POWER"P3V3_STBY"
BODY_TYPE"PLUMBING"
CDS_LIB"mstr_symbols"
SIZE"1B"
VOLTAGE"3.3V";
"G\NAC"4;
%"RES"
"2","(-1850,1525)","0","mstr_discrete","I111";
;
CDS_SEC"1"
CDS_LOCATION"R1M25"
ROOM"USB_REAR"
CDS_LIB"mstr_discrete"
SEC"1"
SEC_TYPE"0402"
BOM_COST"MIO_USB"
PART_NUMBER"G21796-016"
MATERIAL"CHIP"
WATTAGE"1/16W"
PACK_TYPE"0402"
TOLERANCE"1%"
VALUE"10.0K"
LOCATION"R1M25";
"A"
$PN"1"25;
"B"
$PN"2"5;
%"GND"
"1","(-1850,1300)","0","mstr_symbols","I112";
;
VOLTAGE"0"
CDS_LIB"mstr_symbols"
SIZE"1B"
BODY_TYPE"PLUMBING"
HDL_POWER"GND";
"A\NAC"5;
%"CAPP"
"1","(-525,1625)","0","mstr_discrete","I113";
;
CDS_SEC"1"
CDS_LOCATION"C9B8"
CDS_LIB"mstr_discrete"
SEC_TYPE"7343HLF"
SEC"1"
PART_NUMBER"724613-043"
PACK_TYPE"7343HLF"
MATERIAL"POSCAP"
TOLERANCE"20%"
LOCATION"C9B8"
VOLTAGE"10V"
VALUE"330UF";
"B"
$PN"2"6;
"A"
$PN"1"28;
%"GND"
"1","(-525,1425)","0","mstr_symbols","I114";
;
BODY_TYPE"PLUMBING"
SIZE"1B"
VOLTAGE"0"
CDS_LIB"mstr_symbols"
HDL_POWER"GND";
"A\NAC"6;
%"TTL1G08"
"1","(-1725,3275)","0","mstr_ttl","I122";
;
CDS_SEC"1"
$SEC"1"
CDS_LOCATION"U6W10"
BOM_COST"SM_THERM"
ROOM"CPU_FANS"
CDS_LIB"mstr_ttl"
POWER_GROUP"VCC=P3V3_STBY;GND=GND;"
VALUE"NC7SZ08"
PART_NUMBER"D10321-001"
LOCATION"U6W10"
PACK_TYPE"SOTLF"
MATERIAL"IC";
"Y <SIZE-1..0>"
$PN"4"12;
"B <SIZE-1..0>"
$PN"2"17;
"A <SIZE-1..0>"
$PN"1"16;
%"CAP"
"1","(-1175,2950)","0","mstr_discrete","I124";
;
CDS_SEC"1"
$SEC"1"
CDS_LOCATION"C6W10"
BOM_COST"SM_THERM"
ROOM"CPUFANS"
CDS_LIB"mstr_discrete"
LOCATION"C6W10"
VALUE"0.1UF"
VOLTAGE"16V"
TOLERANCE"10%"
MATERIAL"X7R"
PART_NUMBER"A36096-030"
PACK_TYPE"0402LF";
"A"
$PN"1"8;
"B"
$PN"2"7;
%"GND"
"1","(-1175,2750)","0","mstr_symbols","I125";
;
VOLTAGE"0.0V"
BODY_TYPE"PLUMBING"
CDS_LIB"mstr_symbols"
SIZE"1B"
HDL_POWER"GND";
"A\NAC"7;
%"P3V3_STBY"
"1","(-1175,3125)","0","mstr_symbols","I126";
;
VOLTAGE"3.3V"
CDS_LIB"mstr_symbols"
HDL_POWER"P3V3_STBY"
BODY_TYPE"PLUMBING"
SIZE"1B";
"G\NAC"8;
%"RES"
"1","(-5300,4375)","0","mstr_discrete","I16";
;
CDS_SEC"1"
ROOM"USB_REAR"
BOM_COST"MIO_USB"
SEC"1"
SEC_TYPE"0402"
CDS_LIB"mstr_discrete"
PART_NUMBER"G21497-005"
CDS_LOCATION"R1M5"
WATTAGE"1/16W"
VALUE"0.0"
LOCATION"R1M5"
MATERIAL"CHIP"
TOLERANCE"5%"
PACK_TYPE"0402";
"B"
$PN"2"19;
"A"
$PN"1"23;
%"CHOKE_4PIN"
"1","(-5250,4725)","0","mstr_discrete","I30";
;
CDS_SEC"1"
CDS_LIB"mstr_discrete"
ROOM"USB_REAR"
CDS_LOCATION"L1M2"
SEC"1"
SEC_TYPE"SMLF"
BOM_COST"MIO_USB"
PACK_TYPE"SMLF"
VALUE"90 OHM"
PART_NUMBER"752402-015"
MATERIAL"EMPTY"
LOCATION"L1M2";
"B1"
$PN"3"19;
"B2"
$PN"4"18;
"A2"
$PN"2"23;
"A1"
$PN"1"24;
%"RES"
"1","(-5300,5200)","0","mstr_discrete","I31";
;
CDS_SEC"1"
SEC"1"
SEC_TYPE"0402"
BOM_COST"MIO_USB"
ROOM"USB"
CDS_LIB"mstr_discrete"
PART_NUMBER"G21497-005"
CDS_LOCATION"R1M6"
WATTAGE"1/16W"
PACK_TYPE"0402"
VALUE"0.0"
LOCATION"R1M6"
TOLERANCE"5%"
MATERIAL"CHIP";
"B"
$PN"2"18;
"A"
$PN"1"24;
%"CONN9_H51826001"
"2","(-1300,4550)","0","mstr_conn","I69";
;
CDS_LIB"mstr_conn"
$SEC"1"
CDS_SEC"1"
PACK_TYPE"PIP2"
CDS_LOCATION"J9B1"
ROOM"USB_REAR"
PART_NUMBER"H51826-001"
MATERIAL"CONN"
LOCATION"J9B1";
"STDA_SSRXN"
$PN"5"13;
"STDA_SSRXP"
$PN"6"14;
"STDA_SSTXN"
$PN"8"27;
"STDA_SSTXP"
$PN"9"26;
"MH2"
$PN"MH2"9;
"MH1"
$PN"MH1"9;
"DN"
$PN"2"18;
"DP"
$PN"3"19;
"VBUS"
$PN"1"22;
"GND"
$PN"4"10;
"MH4"
$PN"MH4"10;
"MH3"
$PN"MH3"10;
"GND_DRAIN"
$PN"7"15;
%"GND"
"1","(-2550,4075)","0","mstr_symbols","I70";
;
HDL_POWER"GND"
CDS_LIB"mstr_symbols"
BODY_TYPE"PLUMBING"
SIZE"1B"
VOLTAGE"0.0V";
"A\NAC"9;
%"GND"
"1","(-50,4100)","0","mstr_symbols","I71";
;
HDL_POWER"GND"
CDS_LIB"mstr_symbols"
SIZE"1B"
BODY_TYPE"PLUMBING"
VOLTAGE"0.0V";
"A\NAC"10;
%"DIODEAC_DUAL_ARRAY"
"7","(-3950,4100)","0","mstr_discrete","I98";
;
CDS_SEC"1"
CDS_LIB"mstr_discrete"
ROOM"USB_REAR"
CDS_LOCATION"CR1M2"
SEC"1"
SEC_TYPE"SM9"
PACK_TYPE"SM9"
BOM_COST"MIO_USB"
VALUE"ESD3V3U4ULC"
LOCATION"CR1M2"
PART_NUMBER"G18435-001"
MATERIAL"IC";
"AC3"
$PN"5"29;
"AC2"
$PN"4"31;
"AC1"
$PN"2"18;
"AC0"
$PN"1"19;
"OUT3"
$PN"6"21;
"OUT2"
$PN"7"20;
"OUT1"
$PN"8"18;
"OUT0"
$PN"9"19;
"GND<0>"
$PN"3"11;
%"GND"
"1","(-3300,3725)","0","mstr_symbols","I99";
;
HDL_POWER"GND"
VOLTAGE"0.0V"
SIZE"1B"
CDS_LIB"mstr_symbols"
BODY_TYPE"PLUMBING";
"A\NAC"11;
END.
